# TIMECARD (Time Appliance Project (Time Card)) — schematic netlist excerpt (pin names and nets, part order shuffled) for the footprints in the layout excerpt that follows; sources: Cadence DE-HDL packaged netlist, KiCad conversion of R4006-B0001-02_R01.brd

R423  RESISTOR  4.7KOHM 1%  pkg SMC_0402R_H016  page 17 : \1\ = XP3R3V_FPGA ; \2\ = FPGA_IN_LM75B_INT3_N
R366  RESISTOR  33OHM 1%  pkg SMC_0402R_H016  page 26 : \1\ = RGB_LED_I2C_SCL ; \2\ = R_RGB_LED_I2C_SCL

(kicad_pcb
	(version 20260206)
	(generator "pcbnew")
	(generator_version "10.0")
	(general
		(thickness 1.6)
		(legacy_teardrops no)
	)
	(paper "A4")
	(title_block
		(title "timecard-production-celestica-r4006 — R4006-B0001-02_R01.brd")
		(comment 1 "Time Appliance Project (Time Card) / footprints 515-516 of 1113")
	)
	(layers
		(0 "F.Cu" signal "TOP")
		(4 "In1.Cu" signal "L02_GND1")
		(6 "In2.Cu" signal "L03_SIG1")
		(8 "In3.Cu" signal "L04_GND2")
		(10 "In4.Cu" signal "L05_VCC1")
		(12 "In5.Cu" signal "L06_VCC2")
		(14 "In6.Cu" signal "L07_GND3")
		(16 "In7.Cu" signal "L08_SIG2")
		(18 "In8.Cu" signal "L09_GND4")
		(2 "B.Cu" signal "BOTTOM")
		(9 "F.Adhes" user "F.Adhesive")
		(11 "B.Adhes" user "B.Adhesive")
		(13 "F.Paste" user "Package Geometry/Pastemask Top")
		(15 "B.Paste" user "Package Geometry/Pastemask Bottom")
		(5 "F.SilkS" user "Ref Des/Silkscreen Top")
		(7 "B.SilkS" user "Ref Des/Silkscreen Bottom")
		(1 "F.Mask" user "Board Geometry/Soldermask Top")
		(3 "B.Mask" user "Board Geometry/Soldermask Bottom")
		(17 "Dwgs.User" user "User.Drawings")
		(19 "Cmts.User" user "User.Comments")
		(21 "Eco1.User" user "User.Eco1")
		(23 "Eco2.User" user "User.Eco2")
		(25 "Edge.Cuts" user "Board Geometry/Outline")
		(27 "Margin" user)
		(31 "F.CrtYd" user "Package Geometry/Place Bound Top")
		(29 "B.CrtYd" user "Package Geometry/Place Bound Bottom")
		(35 "F.Fab" user "Ref Des/Assembly Top")
		(33 "B.Fab" user "Ref Des/Assembly Bottom")
	)
	(footprint ""
		(layer "F.Cu")
		(at 150.749 -24.511)
		(property "Reference" "R423"
			(at 0.127 2.45237 0)
			(unlocked yes)
			(layer "F.SilkS")
			(effects
				(font
					(size 0.7874 0.5842)
					(thickness 0.1524)
				)
			)
		)
		(property "Value" "VAL*"
			(at 0.02032 2.13233 0)
			(unlocked yes)
			(layer "F.Fab")
			(hide yes)
			(effects
				(font
					(size 0.7874 0.5842)
					(thickness 0.1524)
				)
			)
		)
		(property "Tolerance" "TOL*"
			(at 0.044704 3.05435 0)
			(unlocked yes)
			(layer "Cmts.User")
			(hide yes)
			(effects
				(font
					(size 0.7874 0.5842)
					(thickness 0.1524)
				)
			)
		)
		(property "User Part Number" "PARTNUM*"
			(at 0.02032 4.024884 0)
			(unlocked yes)
			(layer "Cmts.User")
			(hide yes)
			(effects
				(font
					(size 0.7874 0.5842)
					(thickness 0.1524)
				)
			)
		)
		(property "Device Type" "RESISTOR-G155-14701-01,4.7KOHMA"
			(at 0.008382 1.210564 0)
			(unlocked yes)
			(layer "F.Fab")
			(hide yes)
			(effects
				(font
					(size 0.7874 0.5842)
					(thickness 0.1524)
				)
			)
		)
		(duplicate_pad_numbers_are_jumpers no)
		(fp_line
			(start -1.143 -0.5588)
			(end -1.143 0.5588)
			(stroke
				(width 0.1)
				(type default)
			)
			(layer "F.SilkS")
		)
		(fp_line
			(start -1.143 0.5588)
			(end 1.143 0.5588)
			(stroke
				(width 0.1)
				(type default)
			)
			(layer "F.SilkS")
		)
		(fp_line
			(start 1.143 -0.5588)
			(end -1.143 -0.5588)
			(stroke
				(width 0.1)
				(type default)
			)
			(layer "F.SilkS")
		)
		(fp_line
			(start 1.143 0.5588)
			(end 1.143 -0.5588)
			(stroke
				(width 0.1)
				(type default)
			)
			(layer "F.SilkS")
		)
		(fp_rect
			(start -1.143 0.5588)
			(end 1.143 -0.5588)
			(stroke
				(width 0)
				(type default)
			)
			(fill no)
			(layer "F.CrtYd")
		)
		(fp_line
			(start -0.508 -0.3048)
			(end -0.508 0.3048)
			(stroke
				(width 0.1)
				(type default)
			)
			(layer "F.Fab")
		)
		(fp_line
			(start -0.508 0.3048)
			(end 0.508 0.3048)
			(stroke
				(width 0.1)
				(type default)
			)
			(layer "F.Fab")
		)
		(fp_line
			(start 0.508 -0.3048)
			(end -0.508 -0.3048)
			(stroke
				(width 0.1)
				(type default)
			)
			(layer "F.Fab")
		)
		(fp_line
			(start 0.508 0.3048)
			(end 0.508 -0.3048)
			(stroke
				(width 0.1)
				(type default)
			)
			(layer "F.Fab")
		)
		(pad "1" smd rect
			(at -0.5334 0)
			(size 0.7112 0.6096)
			(layers "F.Cu" "F.Mask" "F.Paste")
			(net "XP3R3V_FPGA")
		)
		(pad "2" smd rect
			(at 0.5334 0)
			(size 0.7112 0.6096)
			(layers "F.Cu" "F.Mask" "F.Paste")
			(net "FPGA_IN_LM75B_INT3_N")
		)
		(zone
			(layer "F.Cu")
			(hatch none 0.5)
			(connect_pads
				(clearance 0)
			)
			(min_thickness 0.25)
			(keepout
				(tracks allowed)
				(vias not_allowed)
				(pads allowed)
				(copperpour not_allowed)
				(footprints allowed)
			)
			(placement
				(enabled no)
				(sheetname "")
			)
			(fill
				(thermal_gap 0.5)
				(thermal_bridge_width 0.5)
				(island_removal_mode 0)
			)
			(polygon
				(pts
					(xy 150.6728 -24.2062) (xy 150.8252 -24.2062) (xy 150.8252 -24.8158) (xy 150.6728 -24.8158)
				)
			)
		)
		(zone
			(layer "F.Cu")
			(hatch none 0.5)
			(connect_pads
				(clearance 0)
			)
			(min_thickness 0.25)
			(keepout
				(tracks not_allowed)
				(vias allowed)
				(pads allowed)
				(copperpour not_allowed)
				(footprints allowed)
			)
			(placement
				(enabled no)
				(sheetname "")
			)
			(fill
				(thermal_gap 0.5)
				(thermal_bridge_width 0.5)
				(island_removal_mode 0)
			)
			(polygon
				(pts
					(xy 150.6728 -24.2062) (xy 150.8252 -24.2062) (xy 150.8252 -24.8158) (xy 150.6728 -24.8158)
				)
			)
		)
	)
	(footprint ""
		(layer "F.Cu")
		(at 111.125 -104.521 180)
		(property "Reference" "R366"
			(at -3.175 3.00863 0)
			(unlocked yes)
			(layer "F.SilkS")
			(effects
				(font
					(size 0.7874 0.5842)
					(thickness 0.1524)
				)
			)
		)
		(property "Value" "VAL*"
			(at 0.02032 2.13233 180)
			(unlocked yes)
			(layer "F.Fab")
			(hide yes)
			(effects
				(font
					(size 0.7874 0.5842)
					(thickness 0.1524)
				)
			)
		)
		(property "Tolerance" "TOL*"
			(at 0.044704 3.05435 180)
			(unlocked yes)
			(layer "Cmts.User")
			(hide yes)
			(effects
				(font
					(size 0.7874 0.5842)
					(thickness 0.1524)
				)
			)
		)
		(property "User Part Number" "PARTNUM*"
			(at 0.02032 4.024884 180)
			(unlocked yes)
			(layer "Cmts.User")
			(hide yes)
			(effects
				(font
					(size 0.7874 0.5842)
					(thickness 0.1524)
				)
			)
		)
		(property "Device Type" "RESISTOR-G155-133R0-01,33OHM,1%"
			(at 0.008382 1.210564 180)
			(unlocked yes)
			(layer "F.Fab")
			(hide yes)
			(effects
				(font
					(size 0.7874 0.5842)
					(thickness 0.1524)
				)
			)
		)
		(duplicate_pad_numbers_are_jumpers no)
		(fp_line
			(start 1.143 0.5588)
			(end 1.143 -0.5588)
			(stroke
				(width 0.1)
				(type default)
			)
			(layer "F.SilkS")
		)
		(fp_line
			(start 1.143 -0.5588)
			(end -1.143 -0.5588)
			(stroke
				(width 0.1)
				(type default)
			)
			(layer "F.SilkS")
		)
		(fp_line
			(start -1.143 0.5588)
			(end 1.143 0.5588)
			(stroke
				(width 0.1)
				(type default)
			)
			(layer "F.SilkS")
		)
		(fp_line
			(start -1.143 -0.5588)
			(end -1.143 0.5588)
			(stroke
				(width 0.1)
				(type default)
			)
			(layer "F.SilkS")
		)
		(fp_poly
			(pts
				(xy -1.143 0.5588) (xy 1.143 0.5588) (xy 1.143 -0.5588) (xy -1.143 -0.5588)
			)
			(stroke
				(width 0)
				(type default)
			)
			(fill no)
			(layer "F.CrtYd")
		)
		(fp_line
			(start 0.508 0.3048)
			(end 0.508 -0.3048)
			(stroke
				(width 0.1)
				(type default)
			)
			(layer "F.Fab")
		)
		(fp_line
			(start 0.508 -0.3048)
			(end -0.508 -0.3048)
			(stroke
				(width 0.1)
				(type default)
			)
			(layer "F.Fab")
		)
		(fp_line
			(start -0.508 0.3048)
			(end 0.508 0.3048)
			(stroke
				(width 0.1)
				(type default)
			)
			(layer "F.Fab")
		)
		(fp_line
			(start -0.508 -0.3048)
			(end -0.508 0.3048)
			(stroke
				(width 0.1)
				(type default)
			)
			(layer "F.Fab")
		)
		(pad "1" smd rect
			(at -0.5334 0 180)
			(size 0.7112 0.6096)
			(layers "F.Cu" "F.Mask" "F.Paste")
			(net "RGB_LED_I2C_SCL")
		)
		(pad "2" smd rect
			(at 0.5334 0 180)
			(size 0.7112 0.6096)
			(layers "F.Cu" "F.Mask" "F.Paste")
			(net "R_RGB_LED_I2C_SCL")
		)
		(zone
			(layer "F.Cu")
			(hatch none 0.5)
			(connect_pads
				(clearance 0)
			)
			(min_thickness 0.25)
			(keepout
				(tracks allowed)
				(vias not_allowed)
				(pads allowed)
				(copperpour not_allowed)
				(footprints allowed)
			)
			(placement
				(enabled no)
				(sheetname "")
			)
			(fill
				(thermal_gap 0.5)
				(thermal_bridge_width 0.5)
				(island_removal_mode 0)
			)
			(polygon
				(pts
					(xy 111.2012 -104.8258) (xy 111.0488 -104.8258) (xy 111.0488 -104.2162) (xy 111.2012 -104.2162)
				)
			)
		)
		(zone
			(layer "F.Cu")
			(hatch none 0.5)
			(connect_pads
				(clearance 0)
			)
			(min_thickness 0.25)
			(keepout
				(tracks not_allowed)
				(vias allowed)
				(pads allowed)
				(copperpour not_allowed)
				(footprints allowed)
			)
			(placement
				(enabled no)
				(sheetname "")
			)
			(fill
				(thermal_gap 0.5)
				(thermal_bridge_width 0.5)
				(island_removal_mode 0)
			)
			(polygon
				(pts
					(xy 111.2012 -104.8258) (xy 111.0488 -104.8258) (xy 111.0488 -104.2162) (xy 111.2012 -104.2162)
				)
			)
		)
	)
)
